(kicad_pcb
	(version 20260206)
	(generator "pcbnew")
	(generator_version "10.0")
	(general
		(thickness 1.6)
		(legacy_teardrops no)
	)
	(paper "A4")
	(title_block
		(title "timecard-production-celestica-r4006 — R4006-B0001-02_R01.brd")
		(comment 1 "Time Appliance Project (Time Card) / footprints 966-970 of 1113")
	)
	(layers
		(0 "F.Cu" signal "TOP")
		(4 "In1.Cu" signal "L02_GND1")
		(6 "In2.Cu" signal "L03_SIG1")
		(8 "In3.Cu" signal "L04_GND2")
		(10 "In4.Cu" signal "L05_VCC1")
		(12 "In5.Cu" signal "L06_VCC2")
		(14 "In6.Cu" signal "L07_GND3")
		(16 "In7.Cu" signal "L08_SIG2")
		(18 "In8.Cu" signal "L09_GND4")
		(2 "B.Cu" signal "BOTTOM")
		(9 "F.Adhes" user "F.Adhesive")
		(11 "B.Adhes" user "B.Adhesive")
		(13 "F.Paste" user "Package Geometry/Pastemask Top")
		(15 "B.Paste" user "Package Geometry/Pastemask Bottom")
		(5 "F.SilkS" user "Ref Des/Silkscreen Top")
		(7 "B.SilkS" user "Ref Des/Silkscreen Bottom")
		(1 "F.Mask" user "Board Geometry/Soldermask Top")
		(3 "B.Mask" user "Board Geometry/Soldermask Bottom")
		(17 "Dwgs.User" user "User.Drawings")
		(19 "Cmts.User" user "User.Comments")
		(21 "Eco1.User" user "User.Eco1")
		(23 "Eco2.User" user "User.Eco2")
		(25 "Edge.Cuts" user "Board Geometry/Outline")
		(27 "Margin" user)
		(31 "F.CrtYd" user "Package Geometry/Place Bound Top")
		(29 "B.CrtYd" user "Package Geometry/Place Bound Bottom")
		(35 "F.Fab" user "Ref Des/Assembly Top")
		(33 "B.Fab" user "Ref Des/Assembly Bottom")
	)
	(footprint ""
		(layer "B.Cu")
		(at 102.743 -56.261)
		(property "Reference" "C159"
			(at 2.667 -0.01905 0)
			(unlocked yes)
			(layer "B.SilkS")
			(effects
				(font
					(size 0.635 0.4064)
					(thickness 0.1524)
				)
				(justify mirror)
			)
		)
		(property "Value" "VAL*"
			(at -0.02032 2.13233 0)
			(unlocked yes)
			(layer "B.Fab")
			(hide yes)
			(effects
				(font
					(size 0.7874 0.5842)
					(thickness 0.1524)
				)
				(justify mirror)
			)
		)
		(property "Device Type" "CAPACITOR-G105-0F475-BM,4.7UF,A"
			(at -0.008382 1.210564 0)
			(unlocked yes)
			(layer "B.Fab")
			(hide yes)
			(effects
				(font
					(size 0.7874 0.5842)
					(thickness 0.1524)
				)
				(justify mirror)
			)
		)
		(property "User Part Number" "PARTNUM*"
			(at -0.02032 4.024884 0)
			(unlocked yes)
			(layer "Cmts.User")
			(hide yes)
			(effects
				(font
					(size 0.7874 0.5842)
					(thickness 0.1524)
				)
				(justify mirror)
			)
		)
		(property "Tolerance" "TOL*"
			(at -0.044704 3.05435 0)
			(unlocked yes)
			(layer "Cmts.User")
			(hide yes)
			(effects
				(font
					(size 0.7874 0.5842)
					(thickness 0.1524)
				)
				(justify mirror)
			)
		)
		(duplicate_pad_numbers_are_jumpers no)
		(fp_line
			(start -1.143 -0.5588)
			(end 1.143 -0.5588)
			(stroke
				(width 0.1)
				(type default)
			)
			(layer "B.SilkS")
		)
		(fp_line
			(start -1.143 0.5588)
			(end -1.143 -0.5588)
			(stroke
				(width 0.1)
				(type default)
			)
			(layer "B.SilkS")
		)
		(fp_line
			(start 1.143 -0.5588)
			(end 1.143 0.5588)
			(stroke
				(width 0.1)
				(type default)
			)
			(layer "B.SilkS")
		)
		(fp_line
			(start 1.143 0.5588)
			(end -1.143 0.5588)
			(stroke
				(width 0.1)
				(type default)
			)
			(layer "B.SilkS")
		)
		(fp_rect
			(start -1.143 0.5588)
			(end 1.143 -0.5588)
			(stroke
				(width 0)
				(type default)
			)
			(fill no)
			(layer "B.CrtYd")
		)
		(fp_line
			(start -0.508 -0.3048)
			(end 0.508 -0.3048)
			(stroke
				(width 0.1)
				(type default)
			)
			(layer "B.Fab")
		)
		(fp_line
			(start -0.508 0.3048)
			(end -0.508 -0.3048)
			(stroke
				(width 0.1)
				(type default)
			)
			(layer "B.Fab")
		)
		(fp_line
			(start 0.508 -0.3048)
			(end 0.508 0.3048)
			(stroke
				(width 0.1)
				(type default)
			)
			(layer "B.Fab")
		)
		(fp_line
			(start 0.508 0.3048)
			(end -0.508 0.3048)
			(stroke
				(width 0.1)
				(type default)
			)
			(layer "B.Fab")
		)
		(pad "1" smd rect
			(at 0.5334 0 180)
			(size 0.7112 0.6096)
			(layers "B.Cu" "B.Mask" "B.Paste")
			(net "XP3R3V_FPGA")
		)
		(pad "2" smd rect
			(at -0.5334 0 180)
			(size 0.7112 0.6096)
			(layers "B.Cu" "B.Mask" "B.Paste")
			(net "SG")
		)
		(zone
			(layer "B.Cu")
			(hatch none 0.5)
			(connect_pads
				(clearance 0)
			)
			(min_thickness 0.25)
			(keepout
				(tracks allowed)
				(vias not_allowed)
				(pads allowed)
				(copperpour not_allowed)
				(footprints allowed)
			)
			(placement
				(enabled no)
				(sheetname "")
			)
			(fill
				(thermal_gap 0.5)
				(thermal_bridge_width 0.5)
				(island_removal_mode 0)
			)
			(polygon
				(pts
					(xy 102.6668 -55.9562) (xy 102.8192 -55.9562) (xy 102.8192 -56.5658) (xy 102.6668 -56.5658)
				)
			)
		)
	)
	(footprint ""
		(layer "B.Cu")
		(at 36.9824 -102.5144 180)
		(property "Reference" "C42"
			(at 4.0386 -0.64897 0)
			(unlocked yes)
			(layer "B.SilkS")
			(effects
				(font
					(size 0.7874 0.5842)
					(thickness 0.1524)
				)
				(justify mirror)
			)
		)
		(property "Value" "VAL*"
			(at -0.0762 2.067306 180)
			(unlocked yes)
			(layer "B.Fab")
			(hide yes)
			(effects
				(font
					(size 0.7874 0.5842)
					(thickness 0.1524)
				)
				(justify mirror)
			)
		)
		(property "Device Type" "CAPACITOR-G105-0B222-FK,2200PFA"
			(at -0.0508 1.127506 180)
			(unlocked yes)
			(layer "B.Fab")
			(hide yes)
			(effects
				(font
					(size 0.7874 0.5842)
					(thickness 0.1524)
				)
				(justify mirror)
			)
		)
		(property "User Part Number" "PARTNUM*"
			(at -0.1016 4.023106 180)
			(unlocked yes)
			(layer "Cmts.User")
			(hide yes)
			(effects
				(font
					(size 0.7874 0.5842)
					(thickness 0.1524)
				)
				(justify mirror)
			)
		)
		(property "Tolerance" "TOL*"
			(at -0.0762 3.032506 180)
			(unlocked yes)
			(layer "Cmts.User")
			(hide yes)
			(effects
				(font
					(size 0.7874 0.5842)
					(thickness 0.1524)
				)
				(justify mirror)
			)
		)
		(duplicate_pad_numbers_are_jumpers no)
		(fp_line
			(start 1.143 0.5588)
			(end -1.143 0.5588)
			(stroke
				(width 0.1)
				(type default)
			)
			(layer "B.SilkS")
		)
		(fp_line
			(start 1.143 -0.5588)
			(end 1.143 0.5588)
			(stroke
				(width 0.1)
				(type default)
			)
			(layer "B.SilkS")
		)
		(fp_line
			(start -1.143 0.5588)
			(end -1.143 -0.5588)
			(stroke
				(width 0.1)
				(type default)
			)
			(layer "B.SilkS")
		)
		(fp_line
			(start -1.143 -0.5588)
			(end 1.143 -0.5588)
			(stroke
				(width 0.1)
				(type default)
			)
			(layer "B.SilkS")
		)
		(fp_rect
			(start -1.143 0.5588)
			(end 1.143 -0.5588)
			(stroke
				(width 0)
				(type default)
			)
			(fill no)
			(layer "B.CrtYd")
		)
		(fp_line
			(start 0.508 0.3048)
			(end -0.508 0.3048)
			(stroke
				(width 0.1)
				(type default)
			)
			(layer "B.Fab")
		)
		(fp_line
			(start 0.508 -0.3048)
			(end 0.508 0.3048)
			(stroke
				(width 0.1)
				(type default)
			)
			(layer "B.Fab")
		)
		(fp_line
			(start -0.508 0.3048)
			(end -0.508 -0.3048)
			(stroke
				(width 0.1)
				(type default)
			)
			(layer "B.Fab")
		)
		(fp_line
			(start -0.508 -0.3048)
			(end 0.508 -0.3048)
			(stroke
				(width 0.1)
				(type default)
			)
			(layer "B.Fab")
		)
		(pad "1" smd rect
			(at 0.5334 0)
			(size 0.7112 0.6096)
			(layers "B.Cu" "B.Mask" "B.Paste")
			(net "UNNAMED_516_CAPACITOR_I13_1")
		)
		(pad "2" smd rect
			(at -0.5334 0)
			(size 0.7112 0.6096)
			(layers "B.Cu" "B.Mask" "B.Paste")
			(net "XP5R0V_AGND")
		)
		(zone
			(layer "B.Cu")
			(hatch none 0.5)
			(connect_pads
				(clearance 0)
			)
			(min_thickness 0.25)
			(keepout
				(tracks allowed)
				(vias not_allowed)
				(pads allowed)
				(copperpour not_allowed)
				(footprints allowed)
			)
			(placement
				(enabled no)
				(sheetname "")
			)
			(fill
				(thermal_gap 0.5)
				(thermal_bridge_width 0.5)
				(island_removal_mode 0)
			)
			(polygon
				(pts
					(xy 37.0586 -102.8192) (xy 36.9062 -102.8192) (xy 36.9062 -102.2096) (xy 37.0586 -102.2096)
				)
			)
		)
	)
	(footprint ""
		(layer "B.Cu")
		(at 5.588 -76.835)
		(property "Reference" "R338"
			(at -3.048 -0.46863 0)
			(unlocked yes)
			(layer "B.SilkS")
			(effects
				(font
					(size 0.7874 0.5842)
					(thickness 0.1524)
				)
				(justify mirror)
			)
		)
		(property "Value" "VAL*"
			(at -0.02032 2.13233 0)
			(unlocked yes)
			(layer "B.Fab")
			(hide yes)
			(effects
				(font
					(size 0.7874 0.5842)
					(thickness 0.1524)
				)
				(justify mirror)
			)
		)
		(property "Tolerance" "TOL*"
			(at -0.044704 3.05435 0)
			(unlocked yes)
			(layer "Cmts.User")
			(hide yes)
			(effects
				(font
					(size 0.7874 0.5842)
					(thickness 0.1524)
				)
				(justify mirror)
			)
		)
		(property "User Part Number" "PARTNUM*"
			(at -0.02032 4.024884 0)
			(unlocked yes)
			(layer "Cmts.User")
			(hide yes)
			(effects
				(font
					(size 0.7874 0.5842)
					(thickness 0.1524)
				)
				(justify mirror)
			)
		)
		(property "Device Type" "RESISTOR-G155-11001-01,1KOHM,1%"
			(at -0.008382 1.210564 0)
			(unlocked yes)
			(layer "B.Fab")
			(hide yes)
			(effects
				(font
					(size 0.7874 0.5842)
					(thickness 0.1524)
				)
				(justify mirror)
			)
		)
		(duplicate_pad_numbers_are_jumpers no)
		(fp_line
			(start -1.143 -0.5588)
			(end 1.143 -0.5588)
			(stroke
				(width 0.1)
				(type default)
			)
			(layer "B.SilkS")
		)
		(fp_line
			(start -1.143 0.5588)
			(end -1.143 -0.5588)
			(stroke
				(width 0.1)
				(type default)
			)
			(layer "B.SilkS")
		)
		(fp_line
			(start 1.143 -0.5588)
			(end 1.143 0.5588)
			(stroke
				(width 0.1)
				(type default)
			)
			(layer "B.SilkS")
		)
		(fp_line
			(start 1.143 0.5588)
			(end -1.143 0.5588)
			(stroke
				(width 0.1)
				(type default)
			)
			(layer "B.SilkS")
		)
		(fp_rect
			(start 1.143 0.5588)
			(end -1.143 -0.5588)
			(stroke
				(width 0)
				(type default)
			)
			(fill no)
			(layer "B.CrtYd")
		)
		(fp_line
			(start -0.508 -0.3048)
			(end 0.508 -0.3048)
			(stroke
				(width 0.1)
				(type default)
			)
			(layer "B.Fab")
		)
		(fp_line
			(start -0.508 0.3048)
			(end -0.508 -0.3048)
			(stroke
				(width 0.1)
				(type default)
			)
			(layer "B.Fab")
		)
		(fp_line
			(start 0.508 -0.3048)
			(end 0.508 0.3048)
			(stroke
				(width 0.1)
				(type default)
			)
			(layer "B.Fab")
		)
		(fp_line
			(start 0.508 0.3048)
			(end -0.508 0.3048)
			(stroke
				(width 0.1)
				(type default)
			)
			(layer "B.Fab")
		)
		(pad "1" smd rect
			(at 0.5334 0 180)
			(size 0.7112 0.6096)
			(layers "B.Cu" "B.Mask" "B.Paste")
			(net "UNNAMED_6_LM75BDPTSSOP8_I34_A0")
		)
		(pad "2" smd rect
			(at -0.5334 0 180)
			(size 0.7112 0.6096)
			(layers "B.Cu" "B.Mask" "B.Paste")
			(net "SG")
		)
		(zone
			(layer "B.Cu")
			(hatch none 0.5)
			(connect_pads
				(clearance 0)
			)
			(min_thickness 0.25)
			(keepout
				(tracks allowed)
				(vias not_allowed)
				(pads allowed)
				(copperpour not_allowed)
				(footprints allowed)
			)
			(placement
				(enabled no)
				(sheetname "")
			)
			(fill
				(thermal_gap 0.5)
				(thermal_bridge_width 0.5)
				(island_removal_mode 0)
			)
			(polygon
				(pts
					(xy 5.6642 -76.5302) (xy 5.6642 -77.1398) (xy 5.5118 -77.1398) (xy 5.5118 -76.5302)
				)
			)
		)
	)
	(footprint ""
		(layer "B.Cu")
		(at 115.443 -74.803)
		(property "Reference" "R226"
			(at -0.127 -2.11963 0)
			(unlocked yes)
			(layer "B.SilkS")
			(effects
				(font
					(size 0.7874 0.5842)
					(thickness 0.1524)
				)
				(justify mirror)
			)
		)
		(property "Value" "VAL*"
			(at -0.02032 2.13233 0)
			(unlocked yes)
			(layer "B.Fab")
			(hide yes)
			(effects
				(font
					(size 0.7874 0.5842)
					(thickness 0.1524)
				)
				(justify mirror)
			)
		)
		(property "Device Type" "RESISTOR-G155-13300-01,330OHM,A"
			(at -0.008382 1.210564 0)
			(unlocked yes)
			(layer "B.Fab")
			(hide yes)
			(effects
				(font
					(size 0.7874 0.5842)
					(thickness 0.1524)
				)
				(justify mirror)
			)
		)
		(property "User Part Number" "PARTNUM*"
			(at -0.02032 4.024884 0)
			(unlocked yes)
			(layer "Cmts.User")
			(hide yes)
			(effects
				(font
					(size 0.7874 0.5842)
					(thickness 0.1524)
				)
				(justify mirror)
			)
		)
		(property "Tolerance" "TOL*"
			(at -0.044704 3.05435 0)
			(unlocked yes)
			(layer "Cmts.User")
			(hide yes)
			(effects
				(font
					(size 0.7874 0.5842)
					(thickness 0.1524)
				)
				(justify mirror)
			)
		)
		(duplicate_pad_numbers_are_jumpers no)
		(fp_line
			(start -1.143 -0.5588)
			(end 1.143 -0.5588)
			(stroke
				(width 0.1)
				(type default)
			)
			(layer "B.SilkS")
		)
		(fp_line
			(start -1.143 0.5588)
			(end -1.143 -0.5588)
			(stroke
				(width 0.1)
				(type default)
			)
			(layer "B.SilkS")
		)
		(fp_line
			(start 1.143 -0.5588)
			(end 1.143 0.5588)
			(stroke
				(width 0.1)
				(type default)
			)
			(layer "B.SilkS")
		)
		(fp_line
			(start 1.143 0.5588)
			(end -1.143 0.5588)
			(stroke
				(width 0.1)
				(type default)
			)
			(layer "B.SilkS")
		)
		(fp_rect
			(start -1.143 0.5588)
			(end 1.143 -0.5588)
			(stroke
				(width 0)
				(type default)
			)
			(fill no)
			(layer "B.CrtYd")
		)
		(fp_line
			(start -0.508 -0.3048)
			(end 0.508 -0.3048)
			(stroke
				(width 0.1)
				(type default)
			)
			(layer "B.Fab")
		)
		(fp_line
			(start -0.508 0.3048)
			(end -0.508 -0.3048)
			(stroke
				(width 0.1)
				(type default)
			)
			(layer "B.Fab")
		)
		(fp_line
			(start 0.508 -0.3048)
			(end 0.508 0.3048)
			(stroke
				(width 0.1)
				(type default)
			)
			(layer "B.Fab")
		)
		(fp_line
			(start 0.508 0.3048)
			(end -0.508 0.3048)
			(stroke
				(width 0.1)
				(type default)
			)
			(layer "B.Fab")
		)
		(pad "1" smd rect
			(at 0.5334 0 180)
			(size 0.7112 0.6096)
			(layers "B.Cu" "B.Mask" "B.Paste")
			(net "XP1R8V_FPGA_PG")
		)
		(pad "2" smd rect
			(at -0.5334 0 180)
			(size 0.7112 0.6096)
			(layers "B.Cu" "B.Mask" "B.Paste")
			(net "XP3R3V_FPGA_EN_R")
		)
		(zone
			(layer "B.Cu")
			(hatch none 0.5)
			(connect_pads
				(clearance 0)
			)
			(min_thickness 0.25)
			(keepout
				(tracks allowed)
				(vias not_allowed)
				(pads allowed)
				(copperpour not_allowed)
				(footprints allowed)
			)
			(placement
				(enabled no)
				(sheetname "")
			)
			(fill
				(thermal_gap 0.5)
				(thermal_bridge_width 0.5)
				(island_removal_mode 0)
			)
			(polygon
				(pts
					(xy 115.3668 -74.4982) (xy 115.5192 -74.4982) (xy 115.5192 -75.1078) (xy 115.3668 -75.1078)
				)
			)
		)
	)
	(footprint ""
		(layer "B.Cu")
		(at 112.776 -61.976 -90)
		(property "Reference" "R220"
			(at -3.302 0.03937 270)
			(unlocked yes)
			(layer "B.SilkS")
			(effects
				(font
					(size 0.7874 0.5842)
					(thickness 0.1524)
				)
				(justify mirror)
			)
		)
		(property "Value" "VAL*"
			(at -0.02032 2.13233 270)
			(unlocked yes)
			(layer "B.Fab")
			(hide yes)
			(effects
				(font
					(size 0.7874 0.5842)
					(thickness 0.1524)
				)
				(justify mirror)
			)
		)
		(property "Device Type" "RESISTOR-G155-11001-01,1KOHM,1%"
			(at -0.008382 1.210564 270)
			(unlocked yes)
			(layer "B.Fab")
			(hide yes)
			(effects
				(font
					(size 0.7874 0.5842)
					(thickness 0.1524)
				)
				(justify mirror)
			)
		)
		(property "User Part Number" "PARTNUM*"
			(at -0.02032 4.024884 270)
			(unlocked yes)
			(layer "Cmts.User")
			(hide yes)
			(effects
				(font
					(size 0.7874 0.5842)
					(thickness 0.1524)
				)
				(justify mirror)
			)
		)
		(property "Tolerance" "TOL*"
			(at -0.044704 3.05435 270)
			(unlocked yes)
			(layer "Cmts.User")
			(hide yes)
			(effects
				(font
					(size 0.7874 0.5842)
					(thickness 0.1524)
				)
				(justify mirror)
			)
		)
		(duplicate_pad_numbers_are_jumpers no)
		(fp_line
			(start -1.143 0.5588)
			(end -1.143 -0.5588)
			(stroke
				(width 0.1)
				(type default)
			)
			(layer "B.SilkS")
		)
		(fp_line
			(start 1.143 0.5588)
			(end -1.143 0.5588)
			(stroke
				(width 0.1)
				(type default)
			)
			(layer "B.SilkS")
		)
		(fp_line
			(start -1.143 -0.5588)
			(end 1.143 -0.5588)
			(stroke
				(width 0.1)
				(type default)
			)
			(layer "B.SilkS")
		)
		(fp_line
			(start 1.143 -0.5588)
			(end 1.143 0.5588)
			(stroke
				(width 0.1)
				(type default)
			)
			(layer "B.SilkS")
		)
		(fp_rect
			(start 1.143 0.5588)
			(end -1.143 -0.5588)
			(stroke
				(width 0)
				(type default)
			)
			(fill no)
			(layer "B.CrtYd")
		)
		(fp_line
			(start -0.508 0.3048)
			(end -0.508 -0.3048)
			(stroke
				(width 0.1)
				(type default)
			)
			(layer "B.Fab")
		)
		(fp_line
			(start 0.508 0.3048)
			(end -0.508 0.3048)
			(stroke
				(width 0.1)
				(type default)
			)
			(layer "B.Fab")
		)
		(fp_line
			(start -0.508 -0.3048)
			(end 0.508 -0.3048)
			(stroke
				(width 0.1)
				(type default)
			)
			(layer "B.Fab")
		)
		(fp_line
			(start 0.508 -0.3048)
			(end 0.508 0.3048)
			(stroke
				(width 0.1)
				(type default)
			)
			(layer "B.Fab")
		)
		(pad "1" smd rect
			(at 0.5334 0 90)
			(size 0.7112 0.6096)
			(layers "B.Cu" "B.Mask" "B.Paste")
			(net "FPGA_BRD_REV0")
		)
		(pad "2" smd rect
			(at -0.5334 0 90)
			(size 0.7112 0.6096)
			(layers "B.Cu" "B.Mask" "B.Paste")
			(net "SG")
		)
		(zone
			(layer "B.Cu")
			(hatch none 0.5)
			(connect_pads
				(clearance 0)
			)
			(min_thickness 0.25)
			(keepout
				(tracks allowed)
				(vias not_allowed)
				(pads allowed)
				(copperpour not_allowed)
				(footprints allowed)
			)
			(placement
				(enabled no)
				(sheetname "")
			)
			(fill
				(thermal_gap 0.5)
				(thermal_bridge_width 0.5)
				(island_removal_mode 0)
			)
			(polygon
				(pts
					(xy 112.4712 -61.8998) (xy 113.0808 -61.8998) (xy 113.0808 -62.0522) (xy 112.4712 -62.0522)
				)
			)
		)
	)
)
